# T6G (Grand Teton) — schematic netlist excerpt (pin names and nets, part order shuffled) for the footprints in the layout excerpt that follows; sources: Cadence DE-HDL packaged netlist, KiCad conversion of 04192023_DAF0TMB3IC0_F0TG_MB_C_brd_V02_OCP.brd

R403  Q_RES  1K 1% CHIP  pkg 0402LF  page 27 : A = PVDD18_S5_P0 ; B = JTAG_CPU0_DBREQ_N
PR100  Q_RES  2.2 1% CHIP  pkg 0402LF  page 205 : A = PVDDCR_CPU1_P0_PVCC ; B = PVDDIO_P0_VCC1
PC144_6  Q_CAP  22UF 16V 20% X6S  pkg C0805  page 220 : A = SW_P12V_AUX_PVDDCR_CPU1_P1_FLT ; B = GND

(kicad_pcb
	(version 20260206)
	(generator "pcbnew")
	(generator_version "10.0")
	(general
		(thickness 1.6)
		(legacy_teardrops no)
	)
	(paper "A4")
	(title_block
		(title "04192023_DAF0TMB3IC0_F0TG_MB_C_brd_V02_OCP.brd")
		(comment 1 "Grand Teton / footprints 7493-7495 of 8354")
	)
	(layers
		(0 "F.Cu" signal "TOP")
		(4 "In1.Cu" signal "GND")
		(6 "In2.Cu" signal "IN1")
		(8 "In3.Cu" signal "GND1")
		(10 "In4.Cu" signal "IN2")
		(12 "In5.Cu" signal "GND2")
		(14 "In6.Cu" signal "IN3")
		(16 "In7.Cu" signal "GND3")
		(18 "In8.Cu" signal "VCC")
		(20 "In9.Cu" signal "VCC1")
		(22 "In10.Cu" signal "GND4")
		(24 "In11.Cu" signal "IN4")
		(26 "In12.Cu" signal "GND5")
		(28 "In13.Cu" signal "IN5")
		(30 "In14.Cu" signal "GND6")
		(32 "In15.Cu" signal "IN6")
		(34 "In16.Cu" signal "GND7")
		(2 "B.Cu" signal "BOTTOM")
		(9 "F.Adhes" user "F.Adhesive")
		(11 "B.Adhes" user "B.Adhesive")
		(13 "F.Paste" user "Package Geometry/Pastemask Top")
		(15 "B.Paste" user "Package Geometry/Pastemask Bottom")
		(5 "F.SilkS" user "Ref Des/Silkscreen Top")
		(7 "B.SilkS" user "Ref Des/Silkscreen Bottom")
		(1 "F.Mask" user "Board Geometry/Soldermask Top")
		(3 "B.Mask" user "Board Geometry/Soldermask Bottom")
		(17 "Dwgs.User" user "User.Drawings")
		(19 "Cmts.User" user "User.Comments")
		(21 "Eco1.User" user "User.Eco1")
		(23 "Eco2.User" user "User.Eco2")
		(25 "Edge.Cuts" user "Board Geometry/Outline")
		(27 "Margin" user)
		(31 "F.CrtYd" user "Package Geometry/Place Bound Top")
		(29 "B.CrtYd" user "Package Geometry/Place Bound Bottom")
		(35 "F.Fab" user "Ref Des/Assembly Top")
		(33 "B.Fab" user "Ref Des/Assembly Bottom")
	)
	(footprint ""
		(layer "B.Cu")
		(at 377.234958 -205.101952 -90)
		(property "Reference" "R403"
			(at 0 0 90)
			(layer "B.SilkS")
			(hide yes)
			(effects
				(font
					(size 1.27 1.27)
				)
				(justify mirror)
			)
		)
		(property "Value" ""
			(at 0 0 90)
			(layer "B.Fab")
			(effects
				(font
					(size 1.27 1.27)
				)
				(justify mirror)
			)
		)
		(duplicate_pad_numbers_are_jumpers no)
		(fp_line
			(start -0.7874 0.4064)
			(end 0.7874 0.4064)
			(stroke
				(width 0.1524)
				(type default)
			)
			(layer "B.SilkS")
		)
		(fp_line
			(start 0.7874 0.4064)
			(end 0.7874 -0.4064)
			(stroke
				(width 0.1524)
				(type default)
			)
			(layer "B.SilkS")
		)
		(fp_line
			(start -0.7874 -0.4064)
			(end -0.7874 0.4064)
			(stroke
				(width 0.1524)
				(type default)
			)
			(layer "B.SilkS")
		)
		(fp_line
			(start 0.7874 -0.4064)
			(end -0.7874 -0.4064)
			(stroke
				(width 0.1524)
				(type default)
			)
			(layer "B.SilkS")
		)
		(fp_line
			(start -0.67945 0.3048)
			(end -0.120396 0.3048)
			(stroke
				(width 0.1)
				(type default)
			)
			(layer "B.Fab")
		)
		(fp_line
			(start -0.120396 0.3048)
			(end -0.120396 0.2794)
			(stroke
				(width 0.1)
				(type default)
			)
			(layer "B.Fab")
		)
		(fp_line
			(start 0.12065 0.3048)
			(end 0.67945 0.3048)
			(stroke
				(width 0.1)
				(type default)
			)
			(layer "B.Fab")
		)
		(fp_line
			(start 0.67945 0.3048)
			(end 0.67945 -0.305054)
			(stroke
				(width 0.1)
				(type default)
			)
			(layer "B.Fab")
		)
		(fp_line
			(start -0.120396 0.2794)
			(end 0.12065 0.2794)
			(stroke
				(width 0.1)
				(type default)
			)
			(layer "B.Fab")
		)
		(fp_line
			(start 0.12065 0.2794)
			(end 0.12065 0.3048)
			(stroke
				(width 0.1)
				(type default)
			)
			(layer "B.Fab")
		)
		(fp_line
			(start -0.12065 -0.2794)
			(end -0.12065 -0.3048)
			(stroke
				(width 0.1)
				(type default)
			)
			(layer "B.Fab")
		)
		(fp_line
			(start 0.12065 -0.2794)
			(end -0.12065 -0.2794)
			(stroke
				(width 0.1)
				(type default)
			)
			(layer "B.Fab")
		)
		(fp_line
			(start -0.67945 -0.3048)
			(end -0.67945 0.3048)
			(stroke
				(width 0.1)
				(type default)
			)
			(layer "B.Fab")
		)
		(fp_line
			(start -0.12065 -0.3048)
			(end -0.67945 -0.3048)
			(stroke
				(width 0.1)
				(type default)
			)
			(layer "B.Fab")
		)
		(fp_line
			(start 0.12065 -0.305054)
			(end 0.12065 -0.2794)
			(stroke
				(width 0.1)
				(type default)
			)
			(layer "B.Fab")
		)
		(fp_line
			(start 0.67945 -0.305054)
			(end 0.12065 -0.305054)
			(stroke
				(width 0.1)
				(type default)
			)
			(layer "B.Fab")
		)
		(pad "1" smd circle
			(at 0.40005 0 90)
			(size 0 0)
			(layers "B.Cu" "B.Mask" "B.Paste")
			(net "PVDD18_S5_P0")
		)
		(pad "2" smd circle
			(at -0.40005 0 90)
			(size 0 0)
			(layers "B.Cu" "B.Mask" "B.Paste")
			(net "JTAG_CPU0_DBREQ_N")
		)
	)
	(footprint ""
		(layer "B.Cu")
		(at 104.850946 -340.007194 90)
		(property "Reference" "PC144_6"
			(at 0 0 90)
			(layer "B.SilkS")
			(hide yes)
			(effects
				(font
					(size 1.27 1.27)
				)
				(justify mirror)
			)
		)
		(property "Value" ""
			(at 0 0 90)
			(layer "B.Fab")
			(effects
				(font
					(size 1.27 1.27)
				)
				(justify mirror)
			)
		)
		(duplicate_pad_numbers_are_jumpers no)
		(fp_line
			(start 1.524 -0.762)
			(end -1.524 -0.762)
			(stroke
				(width 0.1524)
				(type default)
			)
			(layer "B.SilkS")
		)
		(fp_line
			(start -1.524 -0.762)
			(end -1.524 0.762)
			(stroke
				(width 0.1524)
				(type default)
			)
			(layer "B.SilkS")
		)
		(fp_line
			(start 1.524 0.762)
			(end 1.524 -0.762)
			(stroke
				(width 0.1524)
				(type default)
			)
			(layer "B.SilkS")
		)
		(fp_line
			(start -1.524 0.762)
			(end 1.524 0.762)
			(stroke
				(width 0.1524)
				(type default)
			)
			(layer "B.SilkS")
		)
		(fp_line
			(start 1.1049 -0.724916)
			(end 1.1049 0.724916)
			(stroke
				(width 0.1)
				(type default)
			)
			(layer "B.Fab")
		)
		(fp_line
			(start -1.1049 -0.724916)
			(end 1.1049 -0.724916)
			(stroke
				(width 0.1)
				(type default)
			)
			(layer "B.Fab")
		)
		(fp_line
			(start 1.1049 0.724916)
			(end -1.1049 0.724916)
			(stroke
				(width 0.1)
				(type default)
			)
			(layer "B.Fab")
		)
		(fp_line
			(start -1.1049 0.724916)
			(end -1.1049 -0.724916)
			(stroke
				(width 0.1)
				(type default)
			)
			(layer "B.Fab")
		)
		(pad "1" smd rect
			(at 0.889 0 90)
			(size 1.016 1.27)
			(layers "B.Cu" "B.Mask" "B.Paste")
			(net "SW_P12V_AUX_PVDDCR_CPU1_P1_FLT")
		)
		(pad "2" smd rect
			(at -0.889 0 90)
			(size 1.016 1.27)
			(layers "B.Cu" "B.Mask" "B.Paste")
			(net "GND")
		)
	)
	(footprint ""
		(layer "B.Cu")
		(at 298.054014 -347.77553 -90)
		(property "Reference" "PR100"
			(at 0 0 90)
			(layer "B.SilkS")
			(hide yes)
			(effects
				(font
					(size 1.27 1.27)
				)
				(justify mirror)
			)
		)
		(property "Value" ""
			(at 0 0 90)
			(layer "B.Fab")
			(effects
				(font
					(size 1.27 1.27)
				)
				(justify mirror)
			)
		)
		(duplicate_pad_numbers_are_jumpers no)
		(fp_line
			(start -0.7874 0.4064)
			(end 0.7874 0.4064)
			(stroke
				(width 0.1524)
				(type default)
			)
			(layer "B.SilkS")
		)
		(fp_line
			(start 0.7874 0.4064)
			(end 0.7874 -0.4064)
			(stroke
				(width 0.1524)
				(type default)
			)
			(layer "B.SilkS")
		)
		(fp_line
			(start -0.7874 -0.4064)
			(end -0.7874 0.4064)
			(stroke
				(width 0.1524)
				(type default)
			)
			(layer "B.SilkS")
		)
		(fp_line
			(start 0.7874 -0.4064)
			(end -0.7874 -0.4064)
			(stroke
				(width 0.1524)
				(type default)
			)
			(layer "B.SilkS")
		)
		(fp_line
			(start -0.67945 0.3048)
			(end -0.120396 0.3048)
			(stroke
				(width 0.1)
				(type default)
			)
			(layer "B.Fab")
		)
		(fp_line
			(start -0.120396 0.3048)
			(end -0.120396 0.2794)
			(stroke
				(width 0.1)
				(type default)
			)
			(layer "B.Fab")
		)
		(fp_line
			(start 0.12065 0.3048)
			(end 0.67945 0.3048)
			(stroke
				(width 0.1)
				(type default)
			)
			(layer "B.Fab")
		)
		(fp_line
			(start 0.67945 0.3048)
			(end 0.67945 -0.305054)
			(stroke
				(width 0.1)
				(type default)
			)
			(layer "B.Fab")
		)
		(fp_line
			(start -0.120396 0.2794)
			(end 0.12065 0.2794)
			(stroke
				(width 0.1)
				(type default)
			)
			(layer "B.Fab")
		)
		(fp_line
			(start 0.12065 0.2794)
			(end 0.12065 0.3048)
			(stroke
				(width 0.1)
				(type default)
			)
			(layer "B.Fab")
		)
		(fp_line
			(start -0.12065 -0.2794)
			(end -0.12065 -0.3048)
			(stroke
				(width 0.1)
				(type default)
			)
			(layer "B.Fab")
		)
		(fp_line
			(start 0.12065 -0.2794)
			(end -0.12065 -0.2794)
			(stroke
				(width 0.1)
				(type default)
			)
			(layer "B.Fab")
		)
		(fp_line
			(start -0.67945 -0.3048)
			(end -0.67945 0.3048)
			(stroke
				(width 0.1)
				(type default)
			)
			(layer "B.Fab")
		)
		(fp_line
			(start -0.12065 -0.3048)
			(end -0.67945 -0.3048)
			(stroke
				(width 0.1)
				(type default)
			)
			(layer "B.Fab")
		)
		(fp_line
			(start 0.12065 -0.305054)
			(end 0.12065 -0.2794)
			(stroke
				(width 0.1)
				(type default)
			)
			(layer "B.Fab")
		)
		(fp_line
			(start 0.67945 -0.305054)
			(end 0.12065 -0.305054)
			(stroke
				(width 0.1)
				(type default)
			)
			(layer "B.Fab")
		)
		(pad "1" smd circle
			(at 0.40005 0 90)
			(size 0 0)
			(layers "B.Cu" "B.Mask" "B.Paste")
			(net "PVDDCR_CPU1_P0_PVCC")
		)
		(pad "2" smd circle
			(at -0.40005 0 90)
			(size 0 0)
			(layers "B.Cu" "B.Mask" "B.Paste")
			(net "PVDDIO_P0_VCC1")
		)
	)
)
